(kicad_pcb
	(version 20260206)
	(generator "pcbnew")
	(generator_version "10.0")
	(general
		(thickness 1.6)
		(legacy_teardrops no)
	)
	(paper "A4")
	(title_block
		(title "v1-chassis-manager — T6M_CM_d_v01_1031_1645.brd")
		(comment 1 "Open CloudServer (Microsoft) / footprints 2433-2442 of 2512")
	)
	(layers
		(0 "F.Cu" signal "TOP")
		(4 "In1.Cu" signal "GND1")
		(6 "In2.Cu" signal "IN1")
		(8 "In3.Cu" signal "VCC1")
		(10 "In4.Cu" signal "VCC2")
		(12 "In5.Cu" signal "GND2")
		(14 "In6.Cu" signal "IN2")
		(16 "In7.Cu" signal "IN3")
		(18 "In8.Cu" signal "GND3")
		(2 "B.Cu" signal "BOTTOM")
		(9 "F.Adhes" user "F.Adhesive")
		(11 "B.Adhes" user "B.Adhesive")
		(13 "F.Paste" user "Package Geometry/Pastemask Top")
		(15 "B.Paste" user "Package Geometry/Pastemask Bottom")
		(5 "F.SilkS" user "Ref Des/Silkscreen Top")
		(7 "B.SilkS" user "Ref Des/Silkscreen Bottom")
		(1 "F.Mask" user "Board Geometry/Soldermask Top")
		(3 "B.Mask" user "Board Geometry/Soldermask Bottom")
		(17 "Dwgs.User" user "User.Drawings")
		(19 "Cmts.User" user "User.Comments")
		(21 "Eco1.User" user "User.Eco1")
		(23 "Eco2.User" user "User.Eco2")
		(25 "Edge.Cuts" user "Board Geometry/Outline")
		(27 "Margin" user)
		(31 "F.CrtYd" user "Package Geometry/Place Bound Top")
		(29 "B.CrtYd" user "Package Geometry/Place Bound Bottom")
		(35 "F.Fab" user "Ref Des/Assembly Top")
		(33 "B.Fab" user "Ref Des/Assembly Bottom")
	)
	(footprint ""
		(layer "B.Cu")
		(at 50.974498 -96.696784 -90)
		(property "Reference" "R79"
			(at -6.405118 4.4958 270)
			(unlocked yes)
			(layer "B.SilkS")
			(effects
				(font
					(size 0.7874 0.5842)
					(thickness 0.1524)
				)
				(justify left mirror)
			)
		)
		(property "Value" ""
			(at 0 0 90)
			(layer "B.Fab")
			(effects
				(font
					(size 1.27 1.27)
				)
				(justify mirror)
			)
		)
		(duplicate_pad_numbers_are_jumpers no)
		(fp_line
			(start -0.7874 0.4064)
			(end 0.7874 0.4064)
			(stroke
				(width 0.1524)
				(type default)
			)
			(layer "B.SilkS")
		)
		(fp_line
			(start 0.7874 0.4064)
			(end 0.7874 -0.4064)
			(stroke
				(width 0.1524)
				(type default)
			)
			(layer "B.SilkS")
		)
		(fp_line
			(start -0.7874 -0.4064)
			(end -0.7874 0.4064)
			(stroke
				(width 0.1524)
				(type default)
			)
			(layer "B.SilkS")
		)
		(fp_line
			(start 0.7874 -0.4064)
			(end -0.7874 -0.4064)
			(stroke
				(width 0.1524)
				(type default)
			)
			(layer "B.SilkS")
		)
		(fp_poly
			(pts
				(xy 0.508 0.2794) (xy 0.508 0.2286) (xy 0.635 0.2286) (xy 0.635 -0.254) (xy 0.5334 -0.254) (xy 0.5334 -0.2794)
				(xy -0.5334 -0.2794) (xy -0.5334 -0.254) (xy -0.635 -0.254) (xy -0.635 0.254) (xy -0.5334 0.254)
				(xy -0.5334 0.2794)
			)
			(stroke
				(width 0)
				(type default)
			)
			(fill no)
			(layer "B.CrtYd")
		)
		(pad "1" smd rect
			(at -0.40005 0 90)
			(size 0.4572 0.508)
			(layers "B.Cu" "B.Mask" "B.Paste")
			(net "GND")
		)
		(pad "2" smd rect
			(at 0.40005 0 90)
			(size 0.4572 0.508)
			(layers "B.Cu" "B.Mask" "B.Paste")
			(net "PD_CPU_NODE1_DFX_GPIO_GRP0_7")
		)
	)
	(footprint ""
		(layer "B.Cu")
		(at 163.128452 -100.83419 180)
		(property "Reference" "C374"
			(at -4.541012 0.095504 0)
			(unlocked yes)
			(layer "B.SilkS")
			(effects
				(font
					(size 0.7874 0.5842)
					(thickness 0.1524)
				)
				(justify left mirror)
			)
		)
		(property "Value" ""
			(at 0 0 0)
			(layer "B.Fab")
			(effects
				(font
					(size 1.27 1.27)
				)
				(justify mirror)
			)
		)
		(duplicate_pad_numbers_are_jumpers no)
		(fp_line
			(start 0.7874 0.4064)
			(end 0.7874 -0.4064)
			(stroke
				(width 0.1524)
				(type default)
			)
			(layer "B.SilkS")
		)
		(fp_line
			(start 0.7874 -0.4064)
			(end -0.7874 -0.4064)
			(stroke
				(width 0.1524)
				(type default)
			)
			(layer "B.SilkS")
		)
		(fp_line
			(start 0 0.381)
			(end 0 -0.381)
			(stroke
				(width 0.1524)
				(type default)
			)
			(layer "B.SilkS")
		)
		(fp_line
			(start -0.7874 0.4064)
			(end 0.7874 0.4064)
			(stroke
				(width 0.1524)
				(type default)
			)
			(layer "B.SilkS")
		)
		(fp_line
			(start -0.7874 -0.4064)
			(end -0.7874 0.4064)
			(stroke
				(width 0.1524)
				(type default)
			)
			(layer "B.SilkS")
		)
		(fp_poly
			(pts
				(xy 0.5334 0.254) (xy 0.635 0.254) (xy 0.635 0.2286) (xy 0.635 -0.254) (xy 0.5334 -0.254) (xy 0.5334 -0.2794)
				(xy -0.5334 -0.2794) (xy -0.5334 -0.254) (xy -0.635 -0.254) (xy -0.635 0.254) (xy -0.5334 0.254)
				(xy -0.5334 0.2794) (xy 0.508 0.2794) (xy 0.5334 0.2794)
			)
			(stroke
				(width 0)
				(type default)
			)
			(fill no)
			(layer "B.CrtYd")
		)
		(pad "1" smd rect
			(at -0.40005 0)
			(size 0.4572 0.508)
			(layers "B.Cu" "B.Mask" "B.Paste")
			(net "GND")
		)
		(pad "2" smd rect
			(at 0.40005 0)
			(size 0.4572 0.508)
			(layers "B.Cu" "B.Mask" "B.Paste")
			(net "P1V05_NODE1")
		)
	)
	(footprint ""
		(layer "B.Cu")
		(at 72.319896 -125.124972 -90)
		(property "Reference" "L17"
			(at 2.831846 -8.211566 270)
			(unlocked yes)
			(layer "B.SilkS")
			(effects
				(font
					(size 0.7874 0.5842)
					(thickness 0.1524)
				)
				(justify mirror)
			)
		)
		(property "Value" ""
			(at 0 0 90)
			(layer "B.Fab")
			(effects
				(font
					(size 1.27 1.27)
				)
				(justify mirror)
			)
		)
		(duplicate_pad_numbers_are_jumpers no)
		(fp_line
			(start -1.2954 0.635)
			(end 1.2954 0.635)
			(stroke
				(width 0.1524)
				(type default)
			)
			(layer "B.SilkS")
		)
		(fp_line
			(start -0.127 -0.5842)
			(end -0.127 0.5842)
			(stroke
				(width 0.1524)
				(type default)
			)
			(layer "B.SilkS")
		)
		(fp_line
			(start 0.127 -0.5842)
			(end 0.127 0.5842)
			(stroke
				(width 0.1524)
				(type default)
			)
			(layer "B.SilkS")
		)
		(fp_line
			(start -1.2954 -0.635)
			(end -1.2954 0.635)
			(stroke
				(width 0.1524)
				(type default)
			)
			(layer "B.SilkS")
		)
		(fp_line
			(start 1.2954 -0.635)
			(end 1.2954 0.635)
			(stroke
				(width 0.1524)
				(type default)
			)
			(layer "B.SilkS")
		)
		(fp_line
			(start 1.2954 -0.635)
			(end -1.2954 -0.635)
			(stroke
				(width 0.1524)
				(type default)
			)
			(layer "B.SilkS")
		)
		(fp_poly
			(pts
				(xy 0.9144 0.508) (xy 0.9144 0.3556) (xy 1.143 0.3556) (xy 1.143 -0.3556) (xy 0.9144 -0.3556) (xy 0.9144 -0.508)
				(xy -0.9144 -0.508) (xy -0.9144 -0.3556) (xy -1.143 -0.3556) (xy -1.143 0.3556) (xy -0.9144 0.3556)
				(xy -0.9144 0.508)
			)
			(stroke
				(width 0)
				(type default)
			)
			(fill no)
			(layer "B.CrtYd")
		)
		(pad "1" smd rect
			(at -0.7366 0)
			(size 0.7112 0.8128)
			(layers "B.Cu" "B.Mask" "B.Paste")
			(net "BMC_NODE1_VCC_1V8_PCIE")
		)
		(pad "2" smd rect
			(at 0.7366 0)
			(size 0.7112 0.8128)
			(layers "B.Cu" "B.Mask" "B.Paste")
			(net "P1V8_NODE1")
		)
	)
	(footprint ""
		(layer "B.Cu")
		(at 63.166498 -96.696784 -90)
		(property "Reference" "R66"
			(at -6.314948 5.033264 270)
			(unlocked yes)
			(layer "B.SilkS")
			(effects
				(font
					(size 0.7874 0.5842)
					(thickness 0.1524)
				)
				(justify left mirror)
			)
		)
		(property "Value" ""
			(at 0 0 90)
			(layer "B.Fab")
			(effects
				(font
					(size 1.27 1.27)
				)
				(justify mirror)
			)
		)
		(duplicate_pad_numbers_are_jumpers no)
		(fp_line
			(start -0.7874 0.4064)
			(end 0.7874 0.4064)
			(stroke
				(width 0.1524)
				(type default)
			)
			(layer "B.SilkS")
		)
		(fp_line
			(start 0.7874 0.4064)
			(end 0.7874 -0.4064)
			(stroke
				(width 0.1524)
				(type default)
			)
			(layer "B.SilkS")
		)
		(fp_line
			(start -0.7874 -0.4064)
			(end -0.7874 0.4064)
			(stroke
				(width 0.1524)
				(type default)
			)
			(layer "B.SilkS")
		)
		(fp_line
			(start 0.7874 -0.4064)
			(end -0.7874 -0.4064)
			(stroke
				(width 0.1524)
				(type default)
			)
			(layer "B.SilkS")
		)
		(fp_poly
			(pts
				(xy 0.508 0.2794) (xy 0.508 0.2286) (xy 0.635 0.2286) (xy 0.635 -0.254) (xy 0.5334 -0.254) (xy 0.5334 -0.2794)
				(xy -0.5334 -0.2794) (xy -0.5334 -0.254) (xy -0.635 -0.254) (xy -0.635 0.254) (xy -0.5334 0.254)
				(xy -0.5334 0.2794)
			)
			(stroke
				(width 0)
				(type default)
			)
			(fill no)
			(layer "B.CrtYd")
		)
		(pad "1" smd rect
			(at -0.40005 0 90)
			(size 0.4572 0.508)
			(layers "B.Cu" "B.Mask" "B.Paste")
			(net "IRQ_CPU_NODE1_SERIAL")
		)
		(pad "2" smd rect
			(at 0.40005 0 90)
			(size 0.4572 0.508)
			(layers "B.Cu" "B.Mask" "B.Paste")
			(net "IRQ_CPU_NODE1_SERIAL_R")
		)
	)
	(footprint ""
		(layer "B.Cu")
		(at 156.828998 -155.89123)
		(property "Reference" "C469"
			(at -3.464814 -0.180594 0)
			(unlocked yes)
			(layer "B.SilkS")
			(effects
				(font
					(size 0.7874 0.5842)
					(thickness 0.1524)
				)
				(justify left mirror)
			)
		)
		(property "Value" ""
			(at 0 0 0)
			(layer "B.Fab")
			(effects
				(font
					(size 1.27 1.27)
				)
				(justify mirror)
			)
		)
		(duplicate_pad_numbers_are_jumpers no)
		(fp_line
			(start -0.7874 -0.4064)
			(end -0.7874 0.4064)
			(stroke
				(width 0.1524)
				(type default)
			)
			(layer "B.SilkS")
		)
		(fp_line
			(start -0.7874 0.4064)
			(end 0.7874 0.4064)
			(stroke
				(width 0.1524)
				(type default)
			)
			(layer "B.SilkS")
		)
		(fp_line
			(start 0 0.381)
			(end 0 -0.381)
			(stroke
				(width 0.1524)
				(type default)
			)
			(layer "B.SilkS")
		)
		(fp_line
			(start 0.7874 -0.4064)
			(end -0.7874 -0.4064)
			(stroke
				(width 0.1524)
				(type default)
			)
			(layer "B.SilkS")
		)
		(fp_line
			(start 0.7874 0.4064)
			(end 0.7874 -0.4064)
			(stroke
				(width 0.1524)
				(type default)
			)
			(layer "B.SilkS")
		)
		(fp_poly
			(pts
				(xy 0.5334 0.254) (xy 0.635 0.254) (xy 0.635 0.2286) (xy 0.635 -0.254) (xy 0.5334 -0.254) (xy 0.5334 -0.2794)
				(xy -0.5334 -0.2794) (xy -0.5334 -0.254) (xy -0.635 -0.254) (xy -0.635 0.254) (xy -0.5334 0.254)
				(xy -0.5334 0.2794) (xy 0.508 0.2794) (xy 0.5334 0.2794)
			)
			(stroke
				(width 0)
				(type default)
			)
			(fill no)
			(layer "B.CrtYd")
		)
		(pad "1" smd rect
			(at -0.40005 0 180)
			(size 0.4572 0.508)
			(layers "B.Cu" "B.Mask" "B.Paste")
			(net "P1V9_LAN2")
		)
		(pad "2" smd rect
			(at 0.40005 0 180)
			(size 0.4572 0.508)
			(layers "B.Cu" "B.Mask" "B.Paste")
			(net "GND")
		)
	)
	(footprint ""
		(layer "B.Cu")
		(at 52.885086 -123.152662 90)
		(property "Reference" "C296"
			(at -55.125874 -42.30497 270)
			(unlocked yes)
			(layer "B.SilkS")
			(effects
				(font
					(size 0.7874 0.5842)
					(thickness 0.1524)
				)
				(justify left mirror)
			)
		)
		(property "Value" ""
			(at 0 0 90)
			(layer "B.Fab")
			(effects
				(font
					(size 1.27 1.27)
				)
				(justify mirror)
			)
		)
		(duplicate_pad_numbers_are_jumpers no)
		(fp_line
			(start 0.7874 -0.4064)
			(end -0.7874 -0.4064)
			(stroke
				(width 0.1524)
				(type default)
			)
			(layer "B.SilkS")
		)
		(fp_line
			(start -0.7874 -0.4064)
			(end -0.7874 0.4064)
			(stroke
				(width 0.1524)
				(type default)
			)
			(layer "B.SilkS")
		)
		(fp_line
			(start 0 0.381)
			(end 0 -0.381)
			(stroke
				(width 0.1524)
				(type default)
			)
			(layer "B.SilkS")
		)
		(fp_line
			(start 0.7874 0.4064)
			(end 0.7874 -0.4064)
			(stroke
				(width 0.1524)
				(type default)
			)
			(layer "B.SilkS")
		)
		(fp_line
			(start -0.7874 0.4064)
			(end 0.7874 0.4064)
			(stroke
				(width 0.1524)
				(type default)
			)
			(layer "B.SilkS")
		)
		(fp_poly
			(pts
				(xy 0.5334 0.254) (xy 0.635 0.254) (xy 0.635 0.2286) (xy 0.635 -0.254) (xy 0.5334 -0.254) (xy 0.5334 -0.2794)
				(xy -0.5334 -0.2794) (xy -0.5334 -0.254) (xy -0.635 -0.254) (xy -0.635 0.254) (xy -0.5334 0.254)
				(xy -0.5334 0.2794) (xy 0.508 0.2794) (xy 0.5334 0.2794)
			)
			(stroke
				(width 0)
				(type default)
			)
			(fill no)
			(layer "B.CrtYd")
		)
		(pad "1" smd rect
			(at -0.40005 0 270)
			(size 0.4572 0.508)
			(layers "B.Cu" "B.Mask" "B.Paste")
			(net "BMC_NODE1_V1PLLAV12")
		)
		(pad "2" smd rect
			(at 0.40005 0 270)
			(size 0.4572 0.508)
			(layers "B.Cu" "B.Mask" "B.Paste")
			(net "GND")
		)
	)
	(footprint ""
		(layer "B.Cu")
		(at 137.65276 -184.951624 90)
		(property "Reference" "R867"
			(at 4.357624 -1.938528 270)
			(unlocked yes)
			(layer "B.SilkS")
			(effects
				(font
					(size 0.7874 0.5842)
					(thickness 0.1524)
				)
				(justify left mirror)
			)
		)
		(property "Value" ""
			(at 0 0 90)
			(layer "B.Fab")
			(effects
				(font
					(size 1.27 1.27)
				)
				(justify mirror)
			)
		)
		(duplicate_pad_numbers_are_jumpers no)
		(fp_line
			(start 0.7874 -0.4064)
			(end -0.7874 -0.4064)
			(stroke
				(width 0.1524)
				(type default)
			)
			(layer "B.SilkS")
		)
		(fp_line
			(start -0.7874 -0.4064)
			(end -0.7874 0.4064)
			(stroke
				(width 0.1524)
				(type default)
			)
			(layer "B.SilkS")
		)
		(fp_line
			(start 0.7874 0.4064)
			(end 0.7874 -0.4064)
			(stroke
				(width 0.1524)
				(type default)
			)
			(layer "B.SilkS")
		)
		(fp_line
			(start -0.7874 0.4064)
			(end 0.7874 0.4064)
			(stroke
				(width 0.1524)
				(type default)
			)
			(layer "B.SilkS")
		)
		(fp_poly
			(pts
				(xy 0.508 0.2794) (xy 0.508 0.2286) (xy 0.635 0.2286) (xy 0.635 -0.254) (xy 0.5334 -0.254) (xy 0.5334 -0.2794)
				(xy -0.5334 -0.2794) (xy -0.5334 -0.254) (xy -0.635 -0.254) (xy -0.635 0.254) (xy -0.5334 0.254)
				(xy -0.5334 0.2794)
			)
			(stroke
				(width 0)
				(type default)
			)
			(fill no)
			(layer "B.CrtYd")
		)
		(pad "1" smd rect
			(at -0.40005 0 270)
			(size 0.4572 0.508)
			(layers "B.Cu" "B.Mask" "B.Paste")
			(net "T9_NODE3_EN")
		)
		(pad "2" smd rect
			(at 0.40005 0 270)
			(size 0.4572 0.508)
			(layers "B.Cu" "B.Mask" "B.Paste")
			(net "T9_NODE3_EN_R")
		)
	)
	(footprint ""
		(layer "B.Cu")
		(at 72.081644 -21.11248 90)
		(property "Reference" "C168"
			(at -5.822188 -0.810006 270)
			(unlocked yes)
			(layer "B.SilkS")
			(effects
				(font
					(size 0.7874 0.5842)
					(thickness 0.1524)
				)
				(justify left mirror)
			)
		)
		(property "Value" ""
			(at 0 0 90)
			(layer "B.Fab")
			(effects
				(font
					(size 1.27 1.27)
				)
				(justify mirror)
			)
		)
		(duplicate_pad_numbers_are_jumpers no)
		(fp_line
			(start 0.7874 -0.4064)
			(end -0.7874 -0.4064)
			(stroke
				(width 0.1524)
				(type default)
			)
			(layer "B.SilkS")
		)
		(fp_line
			(start -0.7874 -0.4064)
			(end -0.7874 0.4064)
			(stroke
				(width 0.1524)
				(type default)
			)
			(layer "B.SilkS")
		)
		(fp_line
			(start 0 0.381)
			(end 0 -0.381)
			(stroke
				(width 0.1524)
				(type default)
			)
			(layer "B.SilkS")
		)
		(fp_line
			(start 0.7874 0.4064)
			(end 0.7874 -0.4064)
			(stroke
				(width 0.1524)
				(type default)
			)
			(layer "B.SilkS")
		)
		(fp_line
			(start -0.7874 0.4064)
			(end 0.7874 0.4064)
			(stroke
				(width 0.1524)
				(type default)
			)
			(layer "B.SilkS")
		)
		(fp_poly
			(pts
				(xy 0.5334 0.254) (xy 0.635 0.254) (xy 0.635 0.2286) (xy 0.635 -0.254) (xy 0.5334 -0.254) (xy 0.5334 -0.2794)
				(xy -0.5334 -0.2794) (xy -0.5334 -0.254) (xy -0.635 -0.254) (xy -0.635 0.254) (xy -0.5334 0.254)
				(xy -0.5334 0.2794) (xy 0.508 0.2794) (xy 0.5334 0.2794)
			)
			(stroke
				(width 0)
				(type default)
			)
			(fill no)
			(layer "B.CrtYd")
		)
		(pad "1" smd rect
			(at -0.40005 0 270)
			(size 0.4572 0.508)
			(layers "B.Cu" "B.Mask" "B.Paste")
			(net "PV_VDDR_NODE1")
		)
		(pad "2" smd rect
			(at 0.40005 0 270)
			(size 0.4572 0.508)
			(layers "B.Cu" "B.Mask" "B.Paste")
			(net "GND")
		)
	)
	(footprint ""
		(layer "B.Cu")
		(at 37.929312 -156.14269 180)
		(property "Reference" "C401"
			(at 6.960616 9.003792 0)
			(unlocked yes)
			(layer "B.SilkS")
			(effects
				(font
					(size 0.7874 0.5842)
					(thickness 0.1524)
				)
				(justify left mirror)
			)
		)
		(property "Value" ""
			(at 0 0 0)
			(layer "B.Fab")
			(effects
				(font
					(size 1.27 1.27)
				)
				(justify mirror)
			)
		)
		(duplicate_pad_numbers_are_jumpers no)
		(fp_line
			(start 0.7874 0.4064)
			(end 0.7874 -0.4064)
			(stroke
				(width 0.1524)
				(type default)
			)
			(layer "B.SilkS")
		)
		(fp_line
			(start 0.7874 -0.4064)
			(end -0.7874 -0.4064)
			(stroke
				(width 0.1524)
				(type default)
			)
			(layer "B.SilkS")
		)
		(fp_line
			(start 0 0.381)
			(end 0 -0.381)
			(stroke
				(width 0.1524)
				(type default)
			)
			(layer "B.SilkS")
		)
		(fp_line
			(start -0.7874 0.4064)
			(end 0.7874 0.4064)
			(stroke
				(width 0.1524)
				(type default)
			)
			(layer "B.SilkS")
		)
		(fp_line
			(start -0.7874 -0.4064)
			(end -0.7874 0.4064)
			(stroke
				(width 0.1524)
				(type default)
			)
			(layer "B.SilkS")
		)
		(fp_poly
			(pts
				(xy 0.5334 0.254) (xy 0.635 0.254) (xy 0.635 0.2286) (xy 0.635 -0.254) (xy 0.5334 -0.254) (xy 0.5334 -0.2794)
				(xy -0.5334 -0.2794) (xy -0.5334 -0.254) (xy -0.635 -0.254) (xy -0.635 0.254) (xy -0.5334 0.254)
				(xy -0.5334 0.2794) (xy 0.508 0.2794) (xy 0.5334 0.2794)
			)
			(stroke
				(width 0)
				(type default)
			)
			(fill no)
			(layer "B.CrtYd")
		)
		(pad "1" smd rect
			(at -0.40005 0)
			(size 0.4572 0.508)
			(layers "B.Cu" "B.Mask" "B.Paste")
			(net "P1V9_LAN1")
		)
		(pad "2" smd rect
			(at 0.40005 0)
			(size 0.4572 0.508)
			(layers "B.Cu" "B.Mask" "B.Paste")
			(net "GND")
		)
	)
	(footprint ""
		(layer "B.Cu")
		(at 107.42676 -185.205624 -90)
		(property "Reference" "C607"
			(at -3.957828 -0.28448 270)
			(unlocked yes)
			(layer "B.SilkS")
			(effects
				(font
					(size 0.7874 0.5842)
					(thickness 0.1524)
				)
				(justify left mirror)
			)
		)
		(property "Value" ""
			(at 0 0 90)
			(layer "B.Fab")
			(effects
				(font
					(size 1.27 1.27)
				)
				(justify mirror)
			)
		)
		(duplicate_pad_numbers_are_jumpers no)
		(fp_line
			(start -0.7874 0.406146)
			(end 0.7874 0.406146)
			(stroke
				(width 0.1524)
				(type default)
			)
			(layer "B.SilkS")
		)
		(fp_line
			(start 0.7874 0.406146)
			(end 0.7874 -0.406146)
			(stroke
				(width 0.1524)
				(type default)
			)
			(layer "B.SilkS")
		)
		(fp_line
			(start 0 0.381)
			(end 0 -0.381)
			(stroke
				(width 0.1524)
				(type default)
			)
			(layer "B.SilkS")
		)
		(fp_line
			(start -0.7874 -0.406146)
			(end -0.7874 0.406146)
			(stroke
				(width 0.1524)
				(type default)
			)
			(layer "B.SilkS")
		)
		(fp_line
			(start 0.7874 -0.406146)
			(end -0.7874 -0.406146)
			(stroke
				(width 0.1524)
				(type default)
			)
			(layer "B.SilkS")
		)
		(fp_poly
			(pts
				(xy 0.5334 0.254) (xy 0.635 0.254) (xy 0.635 0.2286) (xy 0.635 -0.254) (xy 0.5334 -0.254) (xy 0.5334 -0.2794)
				(xy -0.5334 -0.2794) (xy -0.5334 -0.254) (xy -0.635 -0.254) (xy -0.635 0.254) (xy -0.5334 0.254)
				(xy -0.5334 0.2794) (xy 0.508 0.2794) (xy 0.5334 0.2794)
			)
			(stroke
				(width 0)
				(type default)
			)
			(fill no)
			(layer "B.CrtYd")
		)
		(pad "1" smd rect
			(at -0.40005 0 90)
			(size 0.4572 0.508)
			(layers "B.Cu" "B.Mask" "B.Paste")
			(net "PSU_ALERT_N")
		)
		(pad "2" smd rect
			(at 0.40005 0 90)
			(size 0.4572 0.508)
			(layers "B.Cu" "B.Mask" "B.Paste")
			(net "GND")
		)
	)
)
